G04 ================== begin FILE IDENTIFICATION RECORD ==================*
G04 Layout Name:  13130-1b.brd*
G04 Film Name:    DIF_REF_L5*
G04 File Format:  Gerber RS274X*
G04 File Origin:  Cadence Allegro 16.5-S037*
G04 Origin Date:  Thu Nov 13 18:47:02 2014*
G04 *
G04 Layer:  BOARD GEOMETRY/OUTLINE*
G04 Layer:  BOARD GEOMETRY/DIF_REF_L5*
G04 Layer:  BOARD GEOMETRY/PANEL_OUTLINE*
G04 *
G04 Offset:    (0.00 0.00)*
G04 Mirror:    No*
G04 Mode:      Positive*
G04 Rotation:  0*
G04 FullContactRelief:  No*
G04 UndefLineWidth:     6.00*
G04 ================== end FILE IDENTIFICATION RECORD ====================*
%FSLAX35Y35*MOIN*%
%IR0*IPPOS*OFA0.00000B0.00000*MIA0B0*SFA1.00000B1.00000*%
%ADD10C,.004*%
%ADD11C,.006*%
%ADD12C,.0045*%
G75*
%LPD*%
G75*
G54D10*
G01X309192Y118791D02*
X310601Y120200D01*
G01X309192Y117702D02*
Y118791D01*
G01X309194Y117700D02*
X309192Y117702D01*
G01X306994Y117725D02*
X310269Y121000D01*
G01X302711Y115043D02*
X302641Y115113D01*
G01X302711Y114689D02*
Y115043D01*
G01X304200Y113200D02*
X302711Y114689D01*
G01X312500Y113200D02*
X304200D01*
G01X301791Y114123D02*
X301721Y114193D01*
G01X302145Y114123D02*
X301791D01*
G01X303868Y112400D02*
X302145Y114123D01*
G01X312832Y112400D02*
X303868D01*
G01X308284Y123484D02*
X307500Y122700D01*
G01X308284Y123884D02*
Y123484D01*
G01X307834Y124334D02*
X308284Y123884D01*
G01X305734Y124334D02*
X307834D01*
G01X305232Y123832D02*
X305734Y124334D01*
G01X303850Y123832D02*
X305232D01*
G01X303600Y123582D02*
X303850Y123832D01*
G01X303500Y123582D02*
X303600D01*
G01X309084Y123412D02*
X309700Y122796D01*
G01X309084Y124216D02*
Y123412D01*
G01X308166Y125134D02*
X309084Y124216D01*
G01X305402Y125134D02*
X308166D01*
G01X304900Y124632D02*
X305402Y125134D01*
G01X303850Y124632D02*
X304900D01*
G01X303600Y124882D02*
X303850Y124632D01*
G01X303500Y124882D02*
X303600D01*
G01X303100Y131300D02*
X303000D01*
G01X303350Y131050D02*
X303100Y131300D01*
G01X305150Y131050D02*
X303350D01*
G01X307300Y128900D02*
X305150Y131050D01*
G01X313600Y128900D02*
X307300D01*
G01X303100Y130000D02*
X303000D01*
G01X303350Y130250D02*
X303100Y130000D01*
G01X304818Y130250D02*
X303350D01*
G01X306968Y128100D02*
X304818Y130250D01*
G01X313268Y128100D02*
X306968D01*
G01X315732Y120200D02*
X317800Y122268D01*
G01X310601Y120200D02*
X315732D01*
G01X316000Y116700D02*
X312500Y113200D01*
G01X322684Y116700D02*
X316000D01*
G01X327484Y121500D02*
X322684Y116700D01*
G01X313681Y113249D02*
X312832Y112400D01*
G01X314232Y113249D02*
X313681D01*
G01X315081Y114097D02*
X314232Y113249D01*
G01X315081Y114649D02*
Y114097D01*
G01X316332Y115900D02*
X315081Y114649D01*
G01X319836Y115900D02*
X316332D01*
G01X320226Y115510D02*
X319836Y115900D01*
G01X321426Y115510D02*
X320226D01*
G01X321816Y115900D02*
X321426Y115510D01*
G01X323016Y115900D02*
X321816D01*
G01X323865Y116749D02*
X323016Y115900D01*
G01X324416Y116749D02*
X323865D01*
G01X325265Y117597D02*
X324416Y116749D01*
G01X325265Y118149D02*
Y117597D01*
G01X327816Y120700D02*
X325265Y118149D01*
G01X317800Y124700D02*
X313600Y128900D01*
G01X317800Y122268D02*
Y124700D01*
G01X317000Y124368D02*
X313268Y128100D01*
G01X317000Y122600D02*
Y124368D01*
G01X315400Y121000D02*
X317000Y122600D01*
G01X310269Y121000D02*
X315400D01*
G01X332774Y118800D02*
X333534Y118040D01*
G01X332138Y118800D02*
X332774D01*
G01X328050Y114712D02*
X332138Y118800D01*
G01X328050Y112750D02*
Y114712D01*
G01X328300Y112500D02*
X328050Y112750D01*
G01X328300Y112400D02*
Y112500D01*
G01X332701Y119600D02*
X333601Y120500D01*
G01X331806Y119600D02*
X332701D01*
G01X327250Y115044D02*
X331806Y119600D01*
G01X327250Y112750D02*
Y115044D01*
G01X327000Y112500D02*
X327250Y112750D01*
G01X327000Y112400D02*
Y112500D01*
G01X328638Y120700D02*
X327816D01*
G01X329415Y119923D02*
X328638Y120700D01*
G01X328422Y121500D02*
X327484D01*
G01X329308Y122386D02*
X328422Y121500D01*
G01X389803Y117756D02*
X385523Y122036D01*
G01X386899Y119528D02*
X385721D01*
G01X389003Y117424D02*
X386899Y119528D01*
G01X379850Y131600D02*
X403200D01*
G01X379600Y131350D02*
X379850Y131600D01*
G01X379900Y132400D02*
X402868D01*
G01X379650Y132650D02*
X379900Y132400D01*
G01X379600Y132650D02*
X379650D01*
G01X385523Y122036D02*
Y122532D01*
G01X385918Y187700D02*
X384708Y188910D01*
G01X386368Y187700D02*
X385918D01*
G01X386700Y188032D02*
X386368Y187700D01*
G01X386700Y194032D02*
Y188032D01*
G01X388868Y196200D02*
X386700Y194032D01*
G01X384600Y186137D02*
Y186100D01*
G01X385363Y186900D02*
X384600Y186137D01*
G01X386700Y186900D02*
X385363D01*
G01X387500Y187700D02*
X386700Y186900D01*
G01X396535Y82397D02*
X410032Y68900D01*
G01X396535Y88400D02*
Y82397D01*
G01X397300Y89165D02*
X396535Y88400D01*
G01X397300Y89168D02*
Y89165D01*
G01X395735Y82065D02*
X410000Y67800D01*
G01X395735Y95235D02*
Y82065D01*
G01X397100Y96600D02*
X395735Y95235D01*
G01X389803Y115472D02*
Y117756D01*
G01X398507Y106768D02*
X389803Y115472D01*
G01X413184Y106768D02*
X398507D01*
G01X389003Y115140D02*
Y117424D01*
G01X398175Y105968D02*
X389003Y115140D01*
G01X412852Y105968D02*
X398175D01*
G01X390468Y196200D02*
X388868D01*
G01X391563Y197295D02*
X390468Y196200D01*
G01X391563Y197509D02*
Y197295D01*
G01X387500Y193700D02*
Y187700D01*
G01X389200Y195400D02*
X387500Y193700D01*
G01X390800Y195400D02*
X389200D01*
G01X392131Y196731D02*
X390800Y195400D01*
G01X392341Y196731D02*
X392131D01*
G01X390100Y215700D02*
X392100Y213700D01*
G01X390100Y222100D02*
Y215700D01*
G01X391850Y223850D02*
X390100Y222100D01*
G01X391950Y222194D02*
Y220800D01*
G01X392950Y223194D02*
X391950Y222194D01*
G01X410032Y68900D02*
X410800D01*
G01X417155Y102800D02*
X413184Y106768D01*
G01X420900Y102800D02*
X417155D01*
G01X416823Y102000D02*
X412852Y105968D01*
G01X420568Y102000D02*
X416823D01*
G01X415800Y120695D02*
X416904Y119591D01*
G01X415178Y120695D02*
X415800D01*
G01X414033Y119550D02*
X415178Y120695D01*
G01X412167Y119550D02*
X414033D01*
G01X410700Y121017D02*
X412167Y119550D01*
G01X413701Y120350D02*
X414846Y121495D01*
G01X412499Y120350D02*
X413701D01*
G01X411500Y121349D02*
X412499Y120350D01*
G01X410700Y121668D02*
Y121017D01*
G01X410212Y122156D02*
X410700Y121668D01*
G01X410212Y128344D02*
Y122156D01*
G01X410440Y128572D02*
X410212Y128344D01*
G01X410440Y130680D02*
Y128572D01*
G01X408600Y132520D02*
X410440Y130680D01*
G01X404120Y132520D02*
X408600D01*
G01X403200Y131600D02*
X404120Y132520D01*
G01X415746Y121495D02*
X416851Y122600D01*
G01X414846Y121495D02*
X415746D01*
G01X411500Y122000D02*
Y121349D01*
G01X411012Y122488D02*
X411500Y122000D01*
G01X411012Y128012D02*
Y122488D01*
G01X411240Y128240D02*
X411012Y128012D01*
G01X411240Y131012D02*
Y128240D01*
G01X408932Y133320D02*
X411240Y131012D01*
G01X403788Y133320D02*
X408932D01*
G01X402868Y132400D02*
X403788Y133320D01*
G01X421961Y101739D02*
X420900Y102800D01*
G01X422171Y101739D02*
X421961D01*
G01X422241Y101669D02*
X422171Y101739D01*
G01X421393Y101175D02*
X420568Y102000D01*
G01X421393Y100961D02*
Y101175D01*
G01X421463Y100891D02*
X421393Y100961D01*
G01X430886Y122663D02*
X433488Y120061D01*
G01X432688Y113018D02*
X435537Y110169D01*
G01X432688Y119729D02*
Y113018D01*
G01X430554Y121863D02*
X432688Y119729D01*
G01X428104Y122663D02*
X430886D01*
G01X426867Y123900D02*
X428104Y122663D01*
G01X422462Y123900D02*
X426867D01*
G01X420800Y125562D02*
X422462Y123900D01*
G01X420800Y127800D02*
Y125562D01*
G01X422800Y129800D02*
X420800Y127800D01*
G01X422800Y130400D02*
Y129800D01*
G01X423900Y131500D02*
X422800Y130400D01*
G01X427772Y121863D02*
X430554D01*
G01X426535Y123100D02*
X427772Y121863D01*
G01X422130Y123100D02*
X426535D01*
G01X420000Y125230D02*
X422130Y123100D01*
G01X420000Y128132D02*
Y125230D01*
G01X422000Y130132D02*
X420000Y128132D01*
G01X422000Y130724D02*
Y130132D01*
G01X421400Y131324D02*
X422000Y130724D01*
G01X420942Y131324D02*
X421400D01*
G01X421301Y178117D02*
X420922D01*
G01X421784Y178600D02*
X421301Y178117D01*
G01X421784Y179684D02*
Y178600D01*
G01X421196Y180272D02*
X421784Y179684D01*
G01X421196Y182428D02*
Y180272D01*
G01X422708Y183940D02*
X421196Y182428D01*
G01X422584Y179532D02*
X423842Y178274D01*
G01X422584Y180016D02*
Y179532D01*
G01X421996Y180604D02*
X422584Y180016D01*
G01X421996Y182096D02*
Y180604D01*
G01X423040Y183140D02*
X421996Y182096D01*
G01X428962Y169733D02*
X428431Y170264D01*
G01X431601Y169733D02*
X428962D01*
G01X431868Y170000D02*
X431601Y169733D01*
G01X439000Y170000D02*
X431868D01*
G01X428250Y167709D02*
X428238D01*
G01X429474Y168933D02*
X428250Y167709D01*
G01X431933Y168933D02*
X429474D01*
G01X432200Y169200D02*
X431933Y168933D01*
G01X438668Y169200D02*
X432200D01*
G01X430640Y183940D02*
X422708D01*
G01X434347Y187647D02*
X430640Y183940D01*
G01X430972Y183140D02*
X423040D01*
G01X434679Y186847D02*
X430972Y183140D01*
G01X439869Y110969D02*
X440000Y111100D01*
G01X435869Y110969D02*
X439869D01*
G01X433488Y113350D02*
X435869Y110969D01*
G01X433488Y120061D02*
Y113350D01*
G01X439831Y110169D02*
X440000Y110000D01*
G01X435537Y110169D02*
X439831D01*
G01X443200Y165800D02*
X439000Y170000D01*
G01X463844Y165800D02*
X443200D01*
G01X442868Y165000D02*
X438668Y169200D01*
G01X464176Y165000D02*
X442868D01*
G01X436147Y187647D02*
X434347D01*
G01X436509Y188009D02*
X436147Y187647D01*
G01X436509Y188223D02*
Y188009D01*
G01X436579Y188293D02*
X436509Y188223D01*
G01X436479Y186847D02*
X434679D01*
G01X437077Y187445D02*
X436479Y186847D01*
G01X437287Y187445D02*
X437077D01*
G01X437357Y187515D02*
X437287Y187445D01*
G01X464909Y166865D02*
X463844Y165800D01*
G01X465141Y165965D02*
X464176Y165000D01*
G01X465565Y165965D02*
X465141D01*
G54D11*
G01X-31497Y-1D02*
X26377D01*
G01X-35434Y3936D02*
G03X-31497Y-1I3937J0D01*
G01X-35434Y585039D02*
Y3936D01*
G01X-7874Y588976D02*
X-31497D01*
G01D02*
G03X-35434Y585039I0J-3937D01*
G01X-12698Y15747D02*
G03I-6988J0D01*
G01Y573227D02*
G03I-6988J0D01*
G01X822835Y290551D02*
X3937D01*
G03X0Y286614I0J-3937D01*
G01Y61811D01*
G03X3937Y57874I3937J0D01*
G01X53937D01*
G02X57874Y53937I0J-3937D01*
G01Y16142D01*
X338189D01*
Y39961D01*
G02X345669I3740J0D01*
G01Y16142D01*
X389764D01*
Y42126D01*
G02X393701Y46063I3937J0D01*
G01X409449D01*
G02X413386Y42126I0J-3937D01*
G01Y3937D01*
G03X417323Y0I3937J0D01*
G01X822835D01*
G03X826772Y3937I0J3937D01*
G01Y286614D01*
G03X822835Y290551I-3937J0D01*
G01X826773Y286614D02*
G03X822836Y290551I-3937J0D01*
G01X3938D01*
G03X1Y286614I0J-3937D01*
G01Y61811D01*
G03X3938Y57874I3937J0D01*
G01X53938D01*
G02X57875Y53937I0J-3937D01*
G01Y12598D01*
X59844Y10629D01*
X336222D01*
X338190Y12598D01*
Y39960D01*
G02X345671I3740J0D01*
G01Y12598D01*
X347639Y10629D01*
X387797D01*
X389765Y12598D01*
Y42126D01*
G02X393702Y46063I3937J0D01*
G01X409450D01*
G02X413387Y42126I0J-3937D01*
G01Y3937D01*
G03X417324Y0I3937J0D01*
G01X822836D01*
G03X826773Y3937I0J3937D01*
G01Y286614D01*
G01D02*
G03X822836Y290551I-3937J0D01*
G01X3938D01*
G03X1Y286614I0J-3937D01*
G01Y61811D01*
G03X3938Y57874I3937J0D01*
G01X53938D01*
G02X57875Y53937I0J-3937D01*
G01Y12598D01*
X59844Y10629D01*
X336222D01*
X338190Y12598D01*
Y39960D01*
G02X345671I3740J0D01*
G01Y12598D01*
X347639Y10629D01*
X387797D01*
X389765Y12598D01*
Y42126D01*
G02X393702Y46063I3937J0D01*
G01X409450D01*
G02X413387Y42126I0J-3937D01*
G01Y3937D01*
G03X417324Y0I3937J0D01*
G01X822836D01*
G03X826773Y3937I0J3937D01*
G01Y286614D01*
G01X22440Y49999D02*
X-3937D01*
G01X-7874Y53936D02*
Y72440D01*
G01Y53936D02*
G03X-3937Y49999I3937J0D01*
G01X0Y72440D02*
G03X-7874I-3937J0D01*
G01Y103149D02*
G03X0I3937J0D01*
G01X-7874D02*
Y210235D01*
G01X0D02*
G03X-7874I-3937J0D01*
G01Y240944D02*
Y348031D01*
G01Y240944D02*
G03X0I3937J0D01*
G01X-3Y302361D02*
G03X3934Y298424I3937J0D01*
G01X822832D01*
G03X826769Y302361I0J3937D01*
G01Y527164D01*
G03X822832Y531101I-3937J0D01*
G01X772832D01*
G02X768895Y535038I0J3937D01*
G01Y576377D01*
X766926Y578346D01*
X490548D01*
X488580Y576377D01*
Y549015D01*
G02X481099I-3740J0D01*
G01Y576377D01*
X479131Y578346D01*
X438973D01*
X437005Y576377D01*
Y546849D01*
G02X433068Y542912I-3937J0D01*
G01X417320D01*
G02X413383Y546849I0J3937D01*
G01Y585038D01*
G03X409446Y588975I-3937J0D01*
G01X3934D01*
G03X-3Y585038I0J-3937D01*
G01Y302361D01*
G01X0Y348031D02*
G03X-7874I-3937J0D01*
G01Y378739D02*
Y485826D01*
G01Y378739D02*
G03X0I3937J0D01*
G01Y485826D02*
G03X-7874I-3937J0D01*
G01Y516535D02*
Y588976D01*
G01Y516535D02*
G03X0I3937J-1D01*
G01X17137Y687650D02*
Y675650D01*
G01X14837Y687650D02*
X19437D01*
G01X21437Y675650D02*
Y687650D01*
G01Y681850D02*
X21937Y682850D01*
X22437Y683450D01*
X23237Y683650D01*
X23837Y683450D01*
X24537Y682650D01*
X24837Y681450D01*
Y675650D01*
G01X29137Y683650D02*
Y675650D01*
G01Y686850D02*
X28937Y687050D01*
Y687450D01*
X29137Y687650D01*
X29337Y687450D01*
Y687050D01*
X29137Y686850D01*
G01X33637Y677050D02*
X34137Y676250D01*
X34837Y675650D01*
X35437D01*
X36037Y676050D01*
X36437Y676650D01*
X36637Y677450D01*
X36537Y678650D01*
X36137Y679250D01*
X34337Y680450D01*
X33937Y681850D01*
X34137Y682850D01*
X34537Y683450D01*
X35137Y683650D01*
X35737Y683450D01*
X36337Y682850D01*
G01X45737Y672650D02*
X46437Y671850D01*
X47237Y671650D01*
X47937Y671850D01*
X48537Y672850D01*
X48937Y674250D01*
Y683650D01*
G01Y682050D02*
X48537Y682850D01*
X47937Y683450D01*
X47237Y683650D01*
X46437Y683250D01*
X45937Y682450D01*
X45537Y681050D01*
X45337Y679650D01*
X45437Y678450D01*
X45837Y677050D01*
X46437Y676050D01*
X47237Y675650D01*
X47837Y675850D01*
X48537Y676650D01*
X48937Y677450D01*
G01X51637Y681050D02*
X54837D01*
X54537Y682450D01*
X54037Y683250D01*
X53337Y683650D01*
X52637Y683450D01*
X52037Y682850D01*
X51637Y681450D01*
X51437Y680250D01*
Y679050D01*
X51637Y677850D01*
X52137Y676650D01*
X52737Y675850D01*
X53437Y675650D01*
X54137Y676050D01*
X54837Y677250D01*
G01X57737Y675650D02*
Y683650D01*
G01Y682050D02*
X58237Y682850D01*
X58737Y683450D01*
X59437Y683650D01*
X59937Y683450D01*
X60537Y682850D01*
G01X63337Y675650D02*
Y687650D01*
G01Y681650D02*
X63837Y682850D01*
X64437Y683450D01*
X65037Y683650D01*
X65937Y683250D01*
X66537Y682450D01*
X66937Y681050D01*
Y679450D01*
X66737Y677850D01*
X66337Y676650D01*
X65637Y675850D01*
X65037Y675650D01*
X64437Y675850D01*
X63837Y676450D01*
X63337Y677450D01*
G01X69637Y681050D02*
X72837D01*
X72537Y682450D01*
X72037Y683250D01*
X71337Y683650D01*
X70637Y683450D01*
X70037Y682850D01*
X69637Y681450D01*
X69437Y680250D01*
Y679050D01*
X69637Y677850D01*
X70137Y676650D01*
X70737Y675850D01*
X71437Y675650D01*
X72137Y676050D01*
X72837Y677250D01*
G01X75737Y675650D02*
Y683650D01*
G01Y682050D02*
X76237Y682850D01*
X76737Y683450D01*
X77437Y683650D01*
X77937Y683450D01*
X78537Y682850D01*
G01X89137Y683650D02*
Y675650D01*
G01Y686850D02*
X88937Y687050D01*
Y687450D01*
X89137Y687650D01*
X89337Y687450D01*
Y687050D01*
X89137Y686850D01*
G01X93637Y677050D02*
X94137Y676250D01*
X94837Y675650D01*
X95437D01*
X96037Y676050D01*
X96437Y676650D01*
X96637Y677450D01*
X96537Y678650D01*
X96137Y679250D01*
X94337Y680450D01*
X93937Y681850D01*
X94137Y682850D01*
X94537Y683450D01*
X95137Y683650D01*
X95737Y683450D01*
X96337Y682850D01*
G01X105537Y672650D02*
X106237Y671850D01*
X106837Y671650D01*
X107637Y672050D01*
X108237Y673050D01*
X108537Y674850D01*
Y683650D01*
G01Y686850D02*
X108337Y687050D01*
Y687450D01*
X108537Y687650D01*
X108737Y687450D01*
Y687050D01*
X108537Y686850D01*
G01X111437Y683650D02*
Y678050D01*
X111837Y676650D01*
X112437Y675850D01*
X113137Y675650D01*
X113837Y675850D01*
X114437Y676650D01*
X114837Y678050D01*
G01Y675650D02*
Y683650D01*
G01X117637Y677050D02*
X118137Y676250D01*
X118837Y675650D01*
X119437D01*
X120037Y676050D01*
X120437Y676650D01*
X120637Y677450D01*
X120537Y678650D01*
X120137Y679250D01*
X118337Y680450D01*
X117937Y681850D01*
X118137Y682850D01*
X118537Y683450D01*
X119137Y683650D01*
X119737Y683450D01*
X120337Y682850D01*
G01X125137Y687650D02*
Y675650D01*
G01X123737Y683650D02*
X126537D01*
G01X136537Y675650D02*
Y685850D01*
X136737Y686850D01*
X137137Y687450D01*
X137737Y687650D01*
X138337Y687250D01*
X138637Y686250D01*
G01X137437Y682850D02*
X135437D01*
G01X143137Y675650D02*
X142537Y675850D01*
X141937Y676650D01*
X141537Y678050D01*
X141337Y679650D01*
X141537Y681250D01*
X141937Y682650D01*
X142537Y683450D01*
X143137Y683650D01*
X143737Y683450D01*
X144337Y682650D01*
X144737Y681250D01*
X144837Y679650D01*
X144737Y678050D01*
X144337Y676650D01*
X143737Y675850D01*
X143137Y675650D01*
G01X147737D02*
Y683650D01*
G01Y682050D02*
X148237Y682850D01*
X148737Y683450D01*
X149437Y683650D01*
X149937Y683450D01*
X150537Y682850D01*
G01X159037Y672050D02*
X159637Y671650D01*
X160437Y672050D01*
X160937Y672850D01*
X161337Y673850D01*
X161937Y677050D01*
X163237Y683650D01*
G01X160037D02*
X161937Y677050D01*
G01X167137Y675650D02*
X166537Y675850D01*
X165937Y676650D01*
X165537Y678050D01*
X165337Y679650D01*
X165537Y681250D01*
X165937Y682650D01*
X166537Y683450D01*
X167137Y683650D01*
X167737Y683450D01*
X168337Y682650D01*
X168737Y681250D01*
X168837Y679650D01*
X168737Y678050D01*
X168337Y676650D01*
X167737Y675850D01*
X167137Y675650D01*
G01X171437Y683650D02*
Y678050D01*
X171837Y676650D01*
X172437Y675850D01*
X173137Y675650D01*
X173837Y675850D01*
X174437Y676650D01*
X174837Y678050D01*
G01Y675650D02*
Y683650D01*
G01X183737Y675650D02*
Y683650D01*
G01Y682050D02*
X184237Y682850D01*
X184737Y683450D01*
X185437Y683650D01*
X185937Y683450D01*
X186537Y682850D01*
G01X189637Y681050D02*
X192837D01*
X192537Y682450D01*
X192037Y683250D01*
X191337Y683650D01*
X190637Y683450D01*
X190037Y682850D01*
X189637Y681450D01*
X189437Y680250D01*
Y679050D01*
X189637Y677850D01*
X190137Y676650D01*
X190737Y675850D01*
X191437Y675650D01*
X192137Y676050D01*
X192837Y677250D01*
G01X196537Y675650D02*
Y685850D01*
X196737Y686850D01*
X197137Y687450D01*
X197737Y687650D01*
X198337Y687250D01*
X198637Y686250D01*
G01X197437Y682850D02*
X195437D01*
G01X201637Y681050D02*
X204837D01*
X204537Y682450D01*
X204037Y683250D01*
X203337Y683650D01*
X202637Y683450D01*
X202037Y682850D01*
X201637Y681450D01*
X201437Y680250D01*
Y679050D01*
X201637Y677850D01*
X202137Y676650D01*
X202737Y675850D01*
X203437Y675650D01*
X204137Y676050D01*
X204837Y677250D01*
G01X207737Y675650D02*
Y683650D01*
G01Y682050D02*
X208237Y682850D01*
X208737Y683450D01*
X209437Y683650D01*
X209937Y683450D01*
X210537Y682850D01*
G01X213637Y681050D02*
X216837D01*
X216537Y682450D01*
X216037Y683250D01*
X215337Y683650D01*
X214637Y683450D01*
X214037Y682850D01*
X213637Y681450D01*
X213437Y680250D01*
Y679050D01*
X213637Y677850D01*
X214137Y676650D01*
X214737Y675850D01*
X215437Y675650D01*
X216137Y676050D01*
X216837Y677250D01*
G01X219437Y675650D02*
Y683650D01*
G01Y681650D02*
X219837Y682650D01*
X220437Y683450D01*
X221237Y683650D01*
X221937Y683450D01*
X222537Y682650D01*
X222837Y681250D01*
Y675650D01*
G01X228737Y682650D02*
X228037Y683450D01*
X227437Y683650D01*
X226637Y683250D01*
X226037Y682450D01*
X225637Y681050D01*
X225537Y679650D01*
X225637Y678250D01*
X226037Y677050D01*
X226637Y676050D01*
X227437Y675650D01*
X228137Y676050D01*
X228737Y676850D01*
G01X231637Y681050D02*
X234837D01*
X234537Y682450D01*
X234037Y683250D01*
X233337Y683650D01*
X232637Y683450D01*
X232037Y682850D01*
X231637Y681450D01*
X231437Y680250D01*
Y679050D01*
X231637Y677850D01*
X232137Y676650D01*
X232737Y675850D01*
X233437Y675650D01*
X234137Y676050D01*
X234837Y677250D01*
G01X245137Y687650D02*
Y675650D01*
G01X243737Y683650D02*
X246537D01*
G01X251137Y675650D02*
X250537Y675850D01*
X249937Y676650D01*
X249537Y678050D01*
X249337Y679650D01*
X249537Y681250D01*
X249937Y682650D01*
X250537Y683450D01*
X251137Y683650D01*
X251737Y683450D01*
X252337Y682650D01*
X252737Y681250D01*
X252837Y679650D01*
X252737Y678050D01*
X252337Y676650D01*
X251737Y675850D01*
X251137Y675650D01*
G01X262537D02*
Y685850D01*
X262737Y686850D01*
X263137Y687450D01*
X263737Y687650D01*
X264337Y687250D01*
X264637Y686250D01*
G01X263437Y682850D02*
X261437D01*
G01X269137Y683650D02*
Y675650D01*
G01Y686850D02*
X268937Y687050D01*
Y687450D01*
X269137Y687650D01*
X269337Y687450D01*
Y687050D01*
X269137Y686850D01*
G01X273437Y675650D02*
Y683650D01*
G01Y681650D02*
X273837Y682650D01*
X274437Y683450D01*
X275237Y683650D01*
X275937Y683450D01*
X276537Y682650D01*
X276837Y681250D01*
Y675650D01*
G01X282937Y687650D02*
Y675650D01*
G01Y677450D02*
X282537Y676450D01*
X281937Y675850D01*
X281237Y675650D01*
X280437Y676050D01*
X279837Y677050D01*
X279437Y678250D01*
X279337Y679650D01*
X279437Y681050D01*
X279837Y682250D01*
X280437Y683250D01*
X281237Y683650D01*
X281937Y683450D01*
X282437Y683050D01*
X282937Y682250D01*
G01X293137Y687650D02*
Y675650D01*
G01X291737Y683650D02*
X294537D01*
G01X297437Y675650D02*
Y687650D01*
G01Y681850D02*
X297937Y682850D01*
X298437Y683450D01*
X299237Y683650D01*
X299837Y683450D01*
X300537Y682650D01*
X300837Y681450D01*
Y675650D01*
G01X303637Y681050D02*
X306837D01*
X306537Y682450D01*
X306037Y683250D01*
X305337Y683650D01*
X304637Y683450D01*
X304037Y682850D01*
X303637Y681450D01*
X303437Y680250D01*
Y679050D01*
X303637Y677850D01*
X304137Y676650D01*
X304737Y675850D01*
X305437Y675650D01*
X306137Y676050D01*
X306837Y677250D01*
G01X318937Y687650D02*
Y675650D01*
G01Y677450D02*
X318537Y676450D01*
X317937Y675850D01*
X317237Y675650D01*
X316437Y676050D01*
X315837Y677050D01*
X315437Y678250D01*
X315337Y679650D01*
X315437Y681050D01*
X315837Y682250D01*
X316437Y683250D01*
X317237Y683650D01*
X317937Y683450D01*
X318437Y683050D01*
X318937Y682250D01*
G01X323137Y683650D02*
Y675650D01*
G01Y686850D02*
X322937Y687050D01*
Y687450D01*
X323137Y687650D01*
X323337Y687450D01*
Y687050D01*
X323137Y686850D01*
G01X328537Y675650D02*
Y685850D01*
X328737Y686850D01*
X329137Y687450D01*
X329737Y687650D01*
X330337Y687250D01*
X330637Y686250D01*
G01X329437Y682850D02*
X327437D01*
G01X334537Y675650D02*
Y685850D01*
X334737Y686850D01*
X335137Y687450D01*
X335737Y687650D01*
X336337Y687250D01*
X336637Y686250D01*
G01X335437Y682850D02*
X333437D01*
G01X339637Y681050D02*
X342837D01*
X342537Y682450D01*
X342037Y683250D01*
X341337Y683650D01*
X340637Y683450D01*
X340037Y682850D01*
X339637Y681450D01*
X339437Y680250D01*
Y679050D01*
X339637Y677850D01*
X340137Y676650D01*
X340737Y675850D01*
X341437Y675650D01*
X342137Y676050D01*
X342837Y677250D01*
G01X345737Y675650D02*
Y683650D01*
G01Y682050D02*
X346237Y682850D01*
X346737Y683450D01*
X347437Y683650D01*
X347937Y683450D01*
X348537Y682850D01*
G01X351637Y681050D02*
X354837D01*
X354537Y682450D01*
X354037Y683250D01*
X353337Y683650D01*
X352637Y683450D01*
X352037Y682850D01*
X351637Y681450D01*
X351437Y680250D01*
Y679050D01*
X351637Y677850D01*
X352137Y676650D01*
X352737Y675850D01*
X353437Y675650D01*
X354137Y676050D01*
X354837Y677250D01*
G01X357437Y675650D02*
Y683650D01*
G01Y681650D02*
X357837Y682650D01*
X358437Y683450D01*
X359237Y683650D01*
X359937Y683450D01*
X360537Y682650D01*
X360837Y681250D01*
Y675650D01*
G01X365137Y687650D02*
Y675650D01*
G01X363737Y683650D02*
X366537D01*
G01X371137D02*
Y675650D01*
G01Y686850D02*
X370937Y687050D01*
Y687450D01*
X371137Y687650D01*
X371337Y687450D01*
Y687050D01*
X371137Y686850D01*
G01X378937Y675650D02*
Y683650D01*
G01Y682250D02*
X378537Y683050D01*
X377937Y683450D01*
X377237Y683650D01*
X376537Y683250D01*
X375937Y682450D01*
X375537Y681250D01*
X375337Y679650D01*
X375537Y678050D01*
X375937Y676850D01*
X376537Y676050D01*
X377237Y675650D01*
X377937Y675850D01*
X378537Y676450D01*
X378937Y677250D01*
G01X383137Y675650D02*
Y687650D01*
G01X395137D02*
Y675650D01*
G01X393737Y683650D02*
X396537D01*
G01X399737Y675650D02*
Y683650D01*
G01Y682050D02*
X400237Y682850D01*
X400737Y683450D01*
X401437Y683650D01*
X401937Y683450D01*
X402537Y682850D01*
G01X408937Y675650D02*
Y683650D01*
G01Y682250D02*
X408537Y683050D01*
X407937Y683450D01*
X407237Y683650D01*
X406537Y683250D01*
X405937Y682450D01*
X405537Y681250D01*
X405337Y679650D01*
X405537Y678050D01*
X405937Y676850D01*
X406537Y676050D01*
X407237Y675650D01*
X407937Y675850D01*
X408537Y676450D01*
X408937Y677250D01*
G01X414737Y682650D02*
X414037Y683450D01*
X413437Y683650D01*
X412637Y683250D01*
X412037Y682450D01*
X411637Y681050D01*
X411537Y679650D01*
X411637Y678250D01*
X412037Y677050D01*
X412637Y676050D01*
X413437Y675650D01*
X414137Y676050D01*
X414737Y676850D01*
G01X417637Y681050D02*
X420837D01*
X420537Y682450D01*
X420037Y683250D01*
X419337Y683650D01*
X418637Y683450D01*
X418037Y682850D01*
X417637Y681450D01*
X417437Y680250D01*
Y679050D01*
X417637Y677850D01*
X418137Y676650D01*
X418737Y675850D01*
X419437Y675650D01*
X420137Y676050D01*
X420837Y677250D01*
G01X423637Y677050D02*
X424137Y676250D01*
X424837Y675650D01*
X425437D01*
X426037Y676050D01*
X426437Y676650D01*
X426637Y677450D01*
X426537Y678650D01*
X426137Y679250D01*
X424337Y680450D01*
X423937Y681850D01*
X424137Y682850D01*
X424537Y683450D01*
X425137Y683650D01*
X425737Y683450D01*
X426337Y682850D01*
G01X437137Y683650D02*
Y675650D01*
G01Y686850D02*
X436937Y687050D01*
Y687450D01*
X437137Y687650D01*
X437337Y687450D01*
Y687050D01*
X437137Y686850D01*
G01X441437Y675650D02*
Y683650D01*
G01Y681650D02*
X441837Y682650D01*
X442437Y683450D01*
X443237Y683650D01*
X443937Y683450D01*
X444537Y682650D01*
X444837Y681250D01*
Y675650D01*
G01X455137D02*
Y687650D01*
G01X462937Y675650D02*
Y683650D01*
G01Y682250D02*
X462537Y683050D01*
X461937Y683450D01*
X461237Y683650D01*
X460537Y683250D01*
X459937Y682450D01*
X459537Y681250D01*
X459337Y679650D01*
X459537Y678050D01*
X459937Y676850D01*
X460537Y676050D01*
X461237Y675650D01*
X461937Y675850D01*
X462537Y676450D01*
X462937Y677250D01*
G01X465037Y672050D02*
X465637Y671650D01*
X466437Y672050D01*
X466937Y672850D01*
X467337Y673850D01*
X467937Y677050D01*
X469237Y683650D01*
G01X466037D02*
X467937Y677050D01*
G01X471637Y681050D02*
X474837D01*
X474537Y682450D01*
X474037Y683250D01*
X473337Y683650D01*
X472637Y683450D01*
X472037Y682850D01*
X471637Y681450D01*
X471437Y680250D01*
Y679050D01*
X471637Y677850D01*
X472137Y676650D01*
X472737Y675850D01*
X473437Y675650D01*
X474137Y676050D01*
X474837Y677250D01*
G01X477737Y675650D02*
Y683650D01*
G01Y682050D02*
X478237Y682850D01*
X478737Y683450D01*
X479437Y683650D01*
X479937Y683450D01*
X480537Y682850D01*
G01X489137Y687650D02*
Y675650D01*
X493137D01*
G01X494937Y677450D02*
X495537Y676450D01*
X496237Y675850D01*
X497137Y675650D01*
X498037Y676050D01*
X498737Y676850D01*
X499237Y678250D01*
X499337Y679850D01*
X499137Y681450D01*
X498637Y682450D01*
X497937Y683250D01*
X497237Y683450D01*
X496537Y683250D01*
X495637Y682450D01*
X495937Y687650D01*
X498637D01*
G01X26377Y-1D02*
Y46062D01*
G01D02*
G03X22440Y49999I-3937J0D01*
G01X102756Y290550D02*
G03Y298424I0J3937D01*
G01X133465D02*
G03Y290550I0J-3937D01*
G01X299606Y290551D02*
G03Y298425I0J3937D01*
G01X330314D02*
G03Y290551I0J-3937D01*
G01X353350Y224807D02*
X347051D01*
G02Y237406I0J6299D01*
G01X353350D01*
G02Y224807I0J-6299D01*
G01X496457Y290550D02*
G03Y298424I0J3937D01*
G01X527166D02*
G03Y290550I0J-3937D01*
G01X693308D02*
G03Y298424I0J3937D01*
G01X724016D02*
G03Y290550I0J-3937D01*
G01X800393Y588976D02*
Y542913D01*
G01D02*
G03X804330Y538976I3937J0D01*
G01X858267Y588976D02*
X800393D01*
G01X804330Y538976D02*
X830708D01*
G01X834645Y72440D02*
G03X826771I-3937J0D01*
G01Y103149D02*
G03X834645I3937J0D01*
G01Y210235D02*
G03X826771I-3937J0D01*
G01Y240944D02*
G03X834645I3937J0D01*
G01Y348031D02*
G03X826771I-3937J0D01*
G01Y378739D02*
G03X834645I3937J0D01*
G01Y485826D02*
G03X826771I-3937J0D01*
G01Y516535D02*
G03X834645I3937J-1D01*
G01Y535039D02*
G03X830708Y538976I-3937J0D01*
G01X834645Y72440D02*
Y-1D01*
G01D02*
X858267D01*
G01X853444Y15747D02*
G03I-6988J0D01*
G01X834645Y210235D02*
Y103149D01*
G01Y348031D02*
Y240944D01*
G01Y485826D02*
Y378739D01*
G01Y535039D02*
Y516535D01*
G01X853444Y573227D02*
G03I-6988J0D01*
G01X862204Y3936D02*
Y585039D01*
G01X858267Y-1D02*
G03X862204Y3936I0J3937D01*
G01Y585039D02*
G03X858267Y588976I-3937J0D01*
G01X392400Y198346D02*
X391563Y197509D01*
G01X393500Y197890D02*
X392341Y196731D01*
G01X393500Y201944D02*
Y197890D01*
G01X392400Y202400D02*
Y198346D01*
G01X393485Y203485D02*
X392400Y202400D01*
G01X400514Y203485D02*
X393485D01*
G01X403186Y206157D02*
X400514Y203485D01*
G01X393941Y202385D02*
X393500Y201944D01*
G01X400970Y202385D02*
X393941D01*
G01X403642Y205057D02*
X400970Y202385D01*
G01X391850Y229459D02*
Y223850D01*
G01X392950Y229003D02*
Y223194D01*
G01X394869Y232478D02*
X391850Y229459D01*
G01X394869Y233171D02*
Y232478D01*
G01X396142Y234444D02*
X394869Y233171D01*
G01X396835Y234444D02*
X396142D01*
G01X398108Y235717D02*
X396835Y234444D01*
G01X398108Y236410D02*
Y235717D01*
G01X399380Y237682D02*
X398108Y236410D01*
G01X400073Y237682D02*
X399380D01*
G01X401346Y238955D02*
X400073Y237682D01*
G01X401346Y239648D02*
Y238955D01*
G01X402619Y240921D02*
X401346Y239648D01*
G01X403312Y240921D02*
X402619D01*
G01X407293Y243346D02*
X392950Y229003D01*
G01X432394Y68900D02*
X410800D01*
G01X431938Y67800D02*
X410000D01*
G01X408701Y206157D02*
X403186D01*
G01X414544Y212000D02*
X408701Y206157D01*
G01X417500Y212000D02*
X414544D01*
G01X419782Y214282D02*
X417500Y212000D01*
G01X409157Y205057D02*
X403642D01*
G01X415000Y210900D02*
X409157Y205057D01*
G01X417956Y210900D02*
X415000D01*
G01X420238Y213182D02*
X417956Y210900D01*
G01X406837Y244446D02*
X403312Y240921D01*
G01X407300Y243346D02*
X407293D01*
G01X409056Y245102D02*
X407300Y243346D01*
G01X406844Y244446D02*
X406837D01*
G01X407956Y245558D02*
X406844Y244446D01*
G01X407956Y247358D02*
Y245558D01*
G01X407466Y247848D02*
X407956Y247358D01*
G01X407466Y249648D02*
Y247848D01*
G01X407956Y250138D02*
X407466Y249648D01*
G01X407956Y252112D02*
Y250138D01*
G01X411244Y255400D02*
X407956Y252112D01*
G01X415056Y255400D02*
X411244D01*
G01X415546Y255890D02*
X415056Y255400D01*
G01X417346Y255890D02*
X415546D01*
G01X417836Y255400D02*
X417346Y255890D01*
G01X419636Y255400D02*
X417836D01*
G01X409056Y251656D02*
Y245102D01*
G01X411700Y254300D02*
X409056Y251656D01*
G01X425256Y254300D02*
X411700D01*
G01X448194Y53100D02*
X432394Y68900D01*
G01X447738Y52000D02*
X431938Y67800D01*
G01X425200Y98710D02*
X422241Y101669D01*
G01X425200Y93356D02*
Y98710D01*
G01X426956Y91600D02*
X425200Y93356D01*
G01X442700Y91600D02*
X426956D01*
G01X424100Y98254D02*
X421463Y100891D01*
G01X424100Y92900D02*
Y98254D01*
G01X426500Y90500D02*
X424100Y92900D01*
G01X442244Y90500D02*
X426500D01*
G01X421982Y213182D02*
X420238D01*
G01X424122Y215322D02*
X421982Y213182D01*
G01X421526Y214282D02*
X419782D01*
G01X423022Y215778D02*
X421526Y214282D01*
G01X423022Y217378D02*
Y215778D01*
G01X422052Y218348D02*
X423022Y217378D01*
G01X422052Y219930D02*
Y218348D01*
G01X424598Y222476D02*
X422052Y219930D01*
G01X426180Y222476D02*
X424598D01*
G01X427856Y220800D02*
X426180Y222476D01*
G01X428544Y220800D02*
X427856D01*
G01X430944Y223200D02*
X428544Y220800D01*
G01X543900Y223200D02*
X430944D01*
G01X424122Y217834D02*
Y215322D01*
G01X423152Y218804D02*
X424122Y217834D01*
G01X423152Y219474D02*
Y218804D01*
G01X425054Y221376D02*
X423152Y219474D01*
G01X425724Y221376D02*
X425054D01*
G01X427400Y219700D02*
X425724Y221376D01*
G01X429000Y219700D02*
X427400D01*
G01X431400Y222100D02*
X429000Y219700D01*
G01X544356Y222100D02*
X431400D01*
G01X420126Y255890D02*
X419636Y255400D01*
G01X421926Y255890D02*
X420126D01*
G01X422416Y255400D02*
X421926Y255890D01*
G01X424800Y255400D02*
X422416D01*
G01X429900Y260500D02*
X424800Y255400D01*
G01X430356Y259400D02*
X425256Y254300D01*
G01X463791Y259400D02*
X430356D01*
G01X464247Y260500D02*
X429900D01*
G01X458600Y53100D02*
X448194D01*
G01X520100Y52000D02*
X447738D01*
G01X452300Y82000D02*
X442700Y91600D01*
G01X451844Y80900D02*
X442244Y90500D01*
G01X448900Y111100D02*
X440000D01*
G01X449900Y110100D02*
X448900Y111100D01*
G01X448444Y110000D02*
X440000D01*
G01X449444Y109000D02*
X448444Y110000D01*
G01X439950Y191664D02*
X436579Y188293D01*
G01X439950Y193399D02*
Y191664D01*
G01X440450Y193899D02*
X439950Y193399D01*
G01X440450Y197650D02*
Y193899D01*
G01X446900Y204100D02*
X440450Y197650D01*
G01X441050Y191208D02*
X437357Y187515D01*
G01X441050Y192943D02*
Y191208D01*
G01X441550Y193443D02*
X441050Y192943D01*
G01X441550Y197194D02*
Y193443D01*
G01X447356Y203000D02*
X441550Y197194D01*
G01X460700Y204100D02*
X446900D01*
G01X460244Y203000D02*
X447356D01*
G01X459100Y53600D02*
X458600Y53100D01*
G01X460900Y53600D02*
X459100D01*
G01X461400Y53100D02*
X460900Y53600D01*
G01X463212Y53100D02*
X461400D01*
G01X463702Y53590D02*
X463212Y53100D01*
G01X465502Y53590D02*
X463702D01*
G01X531800Y82000D02*
X452300D01*
G01X490043Y80900D02*
X451844D01*
G01X614947Y110100D02*
X449900D01*
G01X614491Y109000D02*
X449444D01*
G01X465800Y199000D02*
X460700Y204100D01*
G01X465344Y197900D02*
X460244Y203000D01*
G01X477991Y245200D02*
X463791Y259400D01*
G01X478447Y246300D02*
X464247Y260500D01*
G01X465992Y53100D02*
X465502Y53590D01*
G01X467792Y53100D02*
X465992D01*
G01X468282Y53590D02*
X467792Y53100D01*
G01X470082Y53590D02*
X468282D01*
G01X470572Y53100D02*
X470082Y53590D01*
G01X472372Y53100D02*
X470572D01*
G01X472862Y53590D02*
X472372Y53100D01*
G01X474662Y53590D02*
X472862D01*
G01X475152Y53100D02*
X474662Y53590D01*
G01X482145Y53100D02*
X475152D01*
G01X464909Y166865D02*
X468344Y170300D01*
G01X468800Y169200D02*
X465565Y165965D01*
G01X468344Y170300D02*
X481244D01*
G01X481700Y169200D02*
X468800D01*
G01X481632Y197900D02*
X465344D01*
G01X482088Y199000D02*
X465800D01*
G01X480247Y246300D02*
X478447D01*
G01X533556Y245200D02*
X477991D01*
G01X482635Y53590D02*
X482145Y53100D01*
G01X484435Y53590D02*
X482635D01*
G01X484925Y53100D02*
X484435Y53590D01*
G01X486725Y53100D02*
X484925D01*
G01X487215Y53590D02*
X486725Y53100D01*
G01X489015Y53590D02*
X487215D01*
G01X489505Y53100D02*
X489015Y53590D01*
G01X491305Y53100D02*
X489505D01*
G01X491795Y53590D02*
X491305Y53100D01*
G01X493595Y53590D02*
X491795D01*
G01X494085Y53100D02*
X493595Y53590D01*
G01X503358Y53100D02*
X494085D01*
G01X490533Y80410D02*
X490043Y80900D01*
G01X492333Y80410D02*
X490533D01*
G01X492823Y80900D02*
X492333Y80410D01*
G01X494820Y80900D02*
X492823D01*
G01X495310Y80410D02*
X494820Y80900D01*
G01X483244Y172300D02*
X597094D01*
G01X481244Y170300D02*
X483244Y172300D01*
G01X483700Y171200D02*
X481700Y169200D01*
G01X597550Y171200D02*
X483700D01*
G01X483888Y197200D02*
X482088Y199000D01*
G01X563024Y197200D02*
X483888D01*
G01X483432Y196100D02*
X481632Y197900D01*
G01X563480Y196100D02*
X483432D01*
G01X480737Y246790D02*
X480247Y246300D01*
G01X482537Y246790D02*
X480737D01*
G01X483027Y246300D02*
X482537Y246790D01*
G01X484827Y246300D02*
X483027D01*
G01X485317Y246790D02*
X484827Y246300D01*
G01X487117Y246790D02*
X485317D01*
G01X487607Y246300D02*
X487117Y246790D01*
G01X489979Y246300D02*
X487607D01*
G01X490469Y246790D02*
X489979Y246300D01*
G01X492269Y246790D02*
X490469D01*
G01X492759Y246300D02*
X492269Y246790D01*
G01X533100Y246300D02*
X492759D01*
G01X503848Y53590D02*
X503358Y53100D01*
G01X505648Y53590D02*
X503848D01*
G01X506138Y53100D02*
X505648Y53590D01*
G01X507938Y53100D02*
X506138D01*
G01X508428Y53590D02*
X507938Y53100D01*
G01X510228Y53590D02*
X508428D01*
G01X510718Y53100D02*
X510228Y53590D01*
G01X497110Y80410D02*
X495310D01*
G01X497600Y80900D02*
X497110Y80410D01*
G01X499400Y80900D02*
X497600D01*
G01X499890Y80410D02*
X499400Y80900D01*
G01X501690Y80410D02*
X499890D01*
G01X502180Y80900D02*
X501690Y80410D01*
G01X503980Y80900D02*
X502180D01*
G01X504470Y80410D02*
X503980Y80900D01*
G01X506270Y80410D02*
X504470D01*
G01X506760Y80900D02*
X506270Y80410D01*
G01X512560Y80900D02*
X506760D01*
G01X512518Y53100D02*
X510718D01*
G01X513008Y53590D02*
X512518Y53100D01*
G01X514808Y53590D02*
X513008D01*
G01X515298Y53100D02*
X514808Y53590D01*
G01X520556Y53100D02*
X515298D01*
G01X521800Y51856D02*
X520556Y53100D01*
G01X521800Y50700D02*
Y51856D01*
G01X522400Y50100D02*
X521800Y50700D01*
G01X524700Y50100D02*
X522400D01*
G01X525300Y50700D02*
X524700Y50100D01*
G01X525300Y52956D02*
Y50700D01*
G01X526444Y54100D02*
X525300Y52956D01*
G01X520700Y51400D02*
X520100Y52000D01*
G01X520700Y50244D02*
Y51400D01*
G01X521944Y49000D02*
X520700Y50244D01*
G01X525156Y49000D02*
X521944D01*
G01X526400Y50244D02*
X525156Y49000D01*
G01X513050Y80410D02*
X512560Y80900D01*
G01X514850Y80410D02*
X513050D01*
G01X515340Y80900D02*
X514850Y80410D01*
G01X517140Y80900D02*
X515340D01*
G01X517630Y80410D02*
X517140Y80900D01*
G01X519430Y80410D02*
X517630D01*
G01X519920Y80900D02*
X519430Y80410D01*
G01X521720Y80900D02*
X519920D01*
G01X522210Y80410D02*
X521720Y80900D01*
G01X524010Y80410D02*
X522210D01*
G01X524500Y80900D02*
X524010Y80410D01*
G01X531344Y80900D02*
X524500D01*
G01X534488Y54100D02*
X526444D01*
G01X543888Y44700D02*
X534488Y54100D01*
G01X526400Y52500D02*
Y50244D01*
G01X526900Y53000D02*
X526400Y52500D01*
G01X534032Y53000D02*
X526900D01*
G01X543432Y43600D02*
X534032Y53000D01*
G01X532900Y80900D02*
X531800Y82000D01*
G01X532900Y77600D02*
Y80900D01*
G01X533500Y77000D02*
X532900Y77600D01*
G01X534800Y77000D02*
X533500D01*
G01X535400Y77600D02*
X534800Y77000D01*
G01X535400Y80500D02*
Y77600D01*
G01X536900Y82000D02*
X535400Y80500D01*
G01X572956Y82000D02*
X536900D01*
G01X531800Y80444D02*
X531344Y80900D01*
G01X531800Y77144D02*
Y80444D01*
G01X533044Y75900D02*
X531800Y77144D01*
G01X535256Y75900D02*
X533044D01*
G01X536500Y77144D02*
X535256Y75900D01*
G01X536500Y80044D02*
Y77144D01*
G01X537356Y80900D02*
X536500Y80044D01*
G01X572500Y80900D02*
X537356D01*
G01X538100Y251300D02*
X533100Y246300D01*
G01X538100Y258444D02*
Y251300D01*
G01X536700Y259844D02*
X538100Y258444D01*
G01X539200Y250844D02*
X533556Y245200D01*
G01X539200Y258900D02*
Y250844D01*
G01X537800Y260300D02*
X539200Y258900D01*
G01X536700Y261351D02*
Y259844D01*
G01X535562Y262489D02*
X536700Y261351D01*
G01X537800Y261443D02*
Y260300D01*
G01X538847Y262489D02*
X537800Y261443D01*
G01X556000Y27607D02*
Y37756D01*
G01X557000Y26607D02*
X556000Y27607D01*
G01X554900Y27151D02*
Y37300D01*
G01X555900Y26151D02*
X554900Y27151D01*
G01X555900Y23507D02*
Y26151D01*
G01X555300Y22907D02*
X555900Y23507D01*
G01X554460Y22907D02*
X555300D01*
G01X556000Y37756D02*
X549056Y44700D01*
G01X548600Y43600D02*
X543432D01*
G01X554900Y37300D02*
X548600Y43600D01*
G01X549056Y44700D02*
X543888D01*
G01X544814Y224114D02*
X543900Y223200D01*
G01X544814Y227659D02*
Y224114D01*
G01X546309Y229154D02*
X544814Y227659D01*
G01X552811Y224412D02*
X548069Y229154D01*
G01X554356Y224412D02*
X552811D01*
G01X555350Y225406D02*
X554356Y224412D01*
G01X555350Y226794D02*
Y225406D01*
G01X552600Y229544D02*
X555350Y226794D01*
G01X545914Y223658D02*
X544356Y222100D01*
G01X545914Y227203D02*
Y223658D01*
G01X546765Y228054D02*
X545914Y227203D01*
G01X547613Y228054D02*
X546765D01*
G01X552355Y223312D02*
X547613Y228054D01*
G01X554812Y223312D02*
X552355D01*
G01X556450Y224950D02*
X554812Y223312D01*
G01X556450Y227250D02*
Y224950D01*
G01X553700Y230000D02*
X556450Y227250D01*
G01X548069Y229154D02*
X546309D01*
G01X552600Y229577D02*
Y229544D01*
G01X550546Y231631D02*
X552600Y229577D01*
G01X550546Y233391D02*
Y231631D01*
G01X552041Y234886D02*
X550546Y233391D01*
G01X553870Y234886D02*
X552041D01*
G01X558156Y230600D02*
X553870Y234886D01*
G01X553700Y230033D02*
Y230000D01*
G01X551646Y232087D02*
X553700Y230033D01*
G01X551646Y232935D02*
Y232087D01*
G01X552497Y233786D02*
X551646Y232935D01*
G01X553414Y233786D02*
X552497D01*
G01X557700Y229500D02*
X553414Y233786D01*
G01X557000Y23507D02*
Y26607D01*
G01X557600Y22907D02*
X557000Y23507D01*
G01X557745Y22907D02*
X557600D01*
G01X569624Y203800D02*
X563024Y197200D01*
G01X570080Y202700D02*
X563480Y196100D01*
G01X584000Y203800D02*
X569624D01*
G01X584456Y202700D02*
X570080D01*
G01X560844Y230600D02*
X558156D01*
G01X561700Y231456D02*
X560844Y230600D01*
G01X561700Y234044D02*
Y231456D01*
G01X561027Y234717D02*
X561700Y234044D01*
G01X561027Y237128D02*
Y234717D01*
G01X561799Y237900D02*
X561027Y237128D01*
G01X561800Y237900D02*
X561799D01*
G01X562300Y238400D02*
X561800Y237900D01*
G01X565000Y238400D02*
X562300D01*
G01X566100Y237300D02*
X565000Y238400D01*
G01X568644Y237300D02*
X566100D01*
G01X569764Y238420D02*
X568644Y237300D01*
G01X569764Y239113D02*
Y238420D01*
G01X571037Y240386D02*
X569764Y239113D01*
G01X571730Y240386D02*
X571037D01*
G01X573403Y242059D02*
X571730Y240386D01*
G01X561300Y229500D02*
X557700D01*
G01X562800Y231000D02*
X561300Y229500D01*
G01X562800Y234500D02*
Y231000D01*
G01X562128Y235172D02*
X562800Y234500D01*
G01X562128Y236672D02*
Y235172D01*
G01X562756Y237300D02*
X562128Y236672D01*
G01X564544Y237300D02*
X562756D01*
G01X565644Y236200D02*
X564544Y237300D01*
G01X569100Y236200D02*
X565644D01*
G01X574503Y241603D02*
X569100Y236200D01*
G01X576000Y26463D02*
Y34168D01*
G01X576800Y25663D02*
X576000Y26463D01*
G01X576800Y23931D02*
Y25663D01*
G01X577824Y22907D02*
X576800Y23931D01*
G01X574900Y26007D02*
Y33712D01*
G01X575700Y25207D02*
X574900Y26007D01*
G01X575700Y24068D02*
Y25207D01*
G01X574539Y22907D02*
X575700Y24068D01*
G01X575501Y34667D02*
Y79455D01*
G01X576000Y34168D02*
X575501Y34667D01*
G01X574401Y34211D02*
Y78999D01*
G01X574900Y33712D02*
X574401Y34211D01*
G01X575501Y79455D02*
X572956Y82000D01*
G01X574401Y78999D02*
X572500Y80900D01*
G01X585700Y205500D02*
X584000Y203800D01*
G01X585700Y209200D02*
Y205500D01*
G01X597000Y220500D02*
X585700Y209200D01*
G01X586800Y205044D02*
X584456Y202700D01*
G01X586800Y208744D02*
Y205044D01*
G01X597456Y219400D02*
X586800Y208744D01*
G01X573403Y245000D02*
Y242059D01*
G01X574503Y248900D02*
Y241603D01*
G01X572900Y245503D02*
X573403Y245000D01*
G01X572900Y247200D02*
Y245503D01*
G01X573403Y247703D02*
X572900Y247200D01*
G01X573403Y249356D02*
Y247703D01*
G01X574500Y250453D02*
X573403Y249356D01*
G01X574500Y261346D02*
Y250453D01*
G01X575600Y249997D02*
X574503Y248900D01*
G01X575600Y261447D02*
Y249997D01*
G01X573357Y262489D02*
X574500Y261346D01*
G01X576642Y262489D02*
X575600Y261447D01*
G01X601894Y177100D02*
X603739D01*
G01X597094Y172300D02*
X601894Y177100D01*
G01X602350Y176000D02*
X597550Y171200D01*
G01X620300Y176000D02*
X602350D01*
G01X640591Y220500D02*
X597000D01*
G01X641047Y219400D02*
X597456D01*
G01X618381Y104675D02*
X617221Y105835D01*
G01X620372Y104675D02*
X618381D01*
G01X616121Y105379D02*
Y107370D01*
G01X617925Y103575D02*
X616121Y105379D01*
G01X619916Y103575D02*
X617925D01*
G01X617221Y107826D02*
X614947Y110100D01*
G01X617221Y105835D02*
Y107826D01*
G01X616121Y107370D02*
X614491Y109000D01*
G01X611099Y177100D02*
X619844D01*
G01X610609Y177590D02*
X611099Y177100D01*
G01X608809Y177590D02*
X610609D01*
G01X608319Y177100D02*
X608809Y177590D01*
G01X606519Y177100D02*
X608319D01*
G01X606029Y177590D02*
X606519Y177100D01*
G01X604229Y177590D02*
X606029D01*
G01X603739Y177100D02*
X604229Y177590D01*
G01X655391Y68100D02*
X619916Y103575D01*
G01X655847Y69200D02*
X620372Y104675D01*
G01X629500Y178000D02*
Y188206D01*
G01X628900Y177400D02*
X629500Y178000D01*
G01X626900Y177400D02*
X628900D01*
G01X626300Y178000D02*
X626900Y177400D01*
G01X626300Y188156D02*
Y178000D01*
G01X620900Y178156D02*
Y188156D01*
G01X619844Y177100D02*
X620900Y178156D01*
G01X622000Y177700D02*
X620300Y176000D01*
G01X622000Y187700D02*
Y177700D01*
G01X625200Y177544D02*
Y187700D01*
G01X626444Y176300D02*
X625200Y177544D01*
G01X629356Y176300D02*
X626444D01*
G01X630600Y177544D02*
X629356Y176300D01*
G01X630600Y187750D02*
Y177544D01*
G01X630744Y189450D02*
X656650D01*
G01X629500Y188206D02*
X630744Y189450D01*
G01X625056Y189400D02*
X626300Y188156D01*
G01X622144Y189400D02*
X625056D01*
G01X620900Y188156D02*
X622144Y189400D01*
G01X622600Y188300D02*
X622000Y187700D01*
G01X624600Y188300D02*
X622600D01*
G01X625200Y187700D02*
X624600Y188300D01*
G01X631200Y188350D02*
X630600Y187750D01*
G01X657106Y188350D02*
X631200D01*
G01X650925Y230834D02*
X640591Y220500D01*
G01X651381Y229734D02*
X641047Y219400D01*
G01X659588Y69200D02*
X655847D01*
G01X679487Y49301D02*
X659588Y69200D01*
G01X659132Y68100D02*
X655391D01*
G01X678387Y48845D02*
X659132Y68100D01*
G01X656650Y189450D02*
X679723Y212523D01*
G01X680179Y211423D02*
X657106Y188350D01*
G01X659066Y230834D02*
X650925D01*
G01X671132Y242900D02*
X659066Y230834D01*
G01X659522Y229734D02*
X651381D01*
G01X671588Y241800D02*
X659522Y229734D01*
G01X679487Y23900D02*
Y49301D01*
G01X680580Y22807D02*
X679487Y23900D01*
G01X678387Y23899D02*
Y48845D01*
G01X677295Y22807D02*
X678387Y23899D01*
G01X679723Y212523D02*
X693335D01*
G01X689397Y242900D02*
X671132D01*
G01X689853Y241800D02*
X671588D01*
G01X693335Y212523D02*
X709000Y228188D01*
G01X693791Y211423D02*
X680179D01*
G01X710100Y227732D02*
X693791Y211423D01*
G01X696985Y250488D02*
X689397Y242900D01*
G01X698085Y250032D02*
X689853Y241800D01*
G01X709000Y228188D02*
Y233800D01*
G01X710100Y233344D02*
Y227732D01*
G01X710273Y235766D02*
X711546Y237039D01*
G01X710273Y235073D02*
Y235766D01*
G01X709000Y233800D02*
X710273Y235073D01*
G01X719700Y242944D02*
X710100Y233344D01*
G01X696985Y261696D02*
Y250488D01*
G01X698085Y261097D02*
Y250032D01*
G01X696192Y262489D02*
X696985Y261696D01*
G01X699477Y262489D02*
X698085Y261097D01*
G01X718600Y243400D02*
Y248844D01*
G01X715477Y240277D02*
X718600Y243400D01*
G01X714784Y240277D02*
X715477D01*
G01X713511Y239004D02*
X714784Y240277D01*
G01X713511Y238311D02*
Y239004D01*
G01X712239Y237039D02*
X713511Y238311D01*
G01X711546Y237039D02*
X712239D01*
G01X719700Y261452D02*
Y242944D01*
G01X718600Y256204D02*
Y261341D01*
G01X718110Y255714D02*
X718600Y256204D01*
G01X718110Y253914D02*
Y255714D01*
G01X718600Y253424D02*
X718110Y253914D01*
G01X718600Y251624D02*
Y253424D01*
G01X718110Y251134D02*
X718600Y251624D01*
G01X718110Y249334D02*
Y251134D01*
G01X718600Y248844D02*
X718110Y249334D01*
G01X718600Y261341D02*
X717452Y262489D01*
G01X720737D02*
X719700Y261452D01*
G54D12*
G01X38050Y200600D02*
X60000D01*
G01X37600Y200150D02*
X38050Y200600D01*
G01X37600Y198800D02*
Y200150D01*
G01X38050Y201900D02*
X60539D01*
G01X37600Y202350D02*
X38050Y201900D01*
G01X37600Y203700D02*
Y202350D01*
G01X40400Y211400D02*
Y212700D01*
G01X40900Y210900D02*
X40400Y211400D01*
G01X46139Y210900D02*
X40900D01*
G01X49314Y207725D02*
X46139Y210900D01*
G01X40400Y208700D02*
Y207800D01*
G01X41300Y209600D02*
X40400Y208700D01*
G01X45600Y209600D02*
X41300D01*
G01X48775Y206425D02*
X45600Y209600D01*
G01X61325Y199275D02*
X76686D01*
G01X60000Y200600D02*
X61325Y199275D01*
G01X61864Y200575D02*
X64085D01*
G01X60539Y201900D02*
X61864Y200575D01*
G01X94039Y207725D02*
X49314D01*
G01X93500Y206425D02*
X48775D01*
G01X76686Y199275D02*
X82261Y193700D01*
G01X77225Y200575D02*
X82800Y195000D01*
G01X71495Y200575D02*
X77225D01*
G01X70655Y201415D02*
X71495Y200575D01*
G01X69305Y201415D02*
X70655D01*
G01X68465Y200575D02*
X69305Y201415D01*
G01X67115Y200575D02*
X68465D01*
G01X66275Y201415D02*
X67115Y200575D01*
G01X64925Y201415D02*
X66275D01*
G01X64085Y200575D02*
X64925Y201415D01*
G01X82261Y193700D02*
X98300D01*
G01X93360Y195000D02*
X98839D01*
G01X92520Y195840D02*
X93360Y195000D01*
G01X91170Y195840D02*
X92520D01*
G01X90330Y195000D02*
X91170Y195840D01*
G01X88980Y195000D02*
X90330D01*
G01X88140Y195840D02*
X88980Y195000D01*
G01X86790Y195840D02*
X88140D01*
G01X85950Y195000D02*
X86790Y195840D01*
G01X82800Y195000D02*
X85950D01*
G01X106073Y195691D02*
X94039Y207725D01*
G01X105534Y194391D02*
X93500Y206425D01*
G01X105000Y187000D02*
X131439D01*
G01X98300Y193700D02*
X105000Y187000D01*
G01X105539Y188300D02*
X130900D01*
G01X98839Y195000D02*
X105539Y188300D01*
G01X131791Y195691D02*
X106073D01*
G01X132330Y194391D02*
X105534D01*
G01X138600Y191500D02*
X140775Y189325D01*
G01X135939Y191500D02*
X138600D01*
G01X131439Y187000D02*
X135939Y191500D01*
G01X139139Y192800D02*
X141314Y190625D01*
G01X135400Y192800D02*
X139139D01*
G01X130900Y188300D02*
X135400Y192800D01*
G01X135255Y199155D02*
X131791Y195691D01*
G01X135794Y197855D02*
X132330Y194391D01*
G01X142170Y197855D02*
X135794D01*
G01X142709Y199155D02*
X135255D01*
G01X140775Y189325D02*
X188836D01*
G01X141314Y190625D02*
X189375D01*
G01X145939Y195925D02*
X142709Y199155D01*
G01X196896Y195925D02*
X145939D01*
G01X145400Y194625D02*
X142170Y197855D01*
G01X196357Y194625D02*
X145400D01*
G01X187641Y150000D02*
X168400Y169241D01*
G01Y172580D02*
X167140Y173840D01*
G01X168400Y169241D02*
Y172580D01*
G01X169700Y172630D02*
X170910Y173840D01*
G01X169700Y169780D02*
Y172630D01*
G01X188941Y150539D02*
X169700Y169780D01*
G01X177500Y165446D02*
X186846Y156100D01*
G01X177500Y169004D02*
Y165446D01*
G01X178800Y165985D02*
X187385Y157400D01*
G01X178800Y168465D02*
Y165985D01*
G01X178496Y170000D02*
X177500Y169004D01*
G01X178496Y171563D02*
Y170000D01*
G01X177159Y172900D02*
X178496Y171563D01*
G01X179796Y169461D02*
X178800Y168465D01*
G01X179796Y171850D02*
Y169461D01*
G01X180931Y172985D02*
X179796Y171850D01*
G01X201899Y134200D02*
X202900Y133199D01*
G01X199311Y146650D02*
X211154D01*
G01X196238Y149723D02*
X199311Y146650D01*
G01X194623Y149723D02*
X196238D01*
G01X199850Y147950D02*
X211693D01*
G01X197140Y150660D02*
X199850Y147950D01*
G01X197140Y152010D02*
Y150660D01*
G01X187641Y147475D02*
Y150000D01*
G01X192216Y142900D02*
X187641Y147475D01*
G01X209600Y142900D02*
X192216D01*
G01X188941Y148014D02*
Y150539D01*
G01X192755Y144200D02*
X188941Y148014D01*
G01X210139Y144200D02*
X192755D01*
G01X186846Y156100D02*
X207008D01*
G01X187385Y157400D02*
X207547D01*
G01X198002Y182750D02*
X203815Y176936D01*
G01X201638Y180953D02*
X202593Y179998D01*
G01X201638Y182141D02*
Y180953D01*
G01X200684Y183095D02*
X201638Y182141D01*
G01X195411Y182750D02*
X198002D01*
G01X188836Y189325D02*
X195411Y182750D01*
G01X199496Y183095D02*
X200684D01*
G01X198541Y184050D02*
X199496Y183095D01*
G01X195950Y184050D02*
X198541D01*
G01X189375Y190625D02*
X195950Y184050D01*
G01X198296Y194525D02*
X196896Y195925D01*
G01X204214Y194525D02*
X198296D01*
G01X197757Y193225D02*
X196357Y194625D01*
G01X203675Y193225D02*
X197757D01*
G01X202900Y130800D02*
X221221Y112479D01*
G01X204200Y131339D02*
X221760Y113779D01*
G01X216250Y132448D02*
X223948Y124750D01*
G01X216250Y141554D02*
Y132448D01*
G01X217550Y132987D02*
X224487Y126050D01*
G01X217550Y142093D02*
Y132987D01*
G01X202900Y133199D02*
Y130800D01*
G01X204200Y133020D02*
Y131339D01*
G01X205380Y134200D02*
X204200Y133020D01*
G01X212500Y130894D02*
Y140000D01*
G01X222394Y121000D02*
X212500Y130894D01*
G01X213800Y131433D02*
Y140539D01*
G01X222933Y122300D02*
X213800Y131433D01*
G01X211154Y146650D02*
X216250Y141554D01*
G01X211693Y147950D02*
X217550Y142093D01*
G01X207008Y156100D02*
X220000Y143108D01*
G01X207547Y157400D02*
X221300Y143647D01*
G01X212500Y140000D02*
X209600Y142900D01*
G01X213800Y140539D02*
X210139Y144200D01*
G01X213504Y171446D02*
X261368Y123582D01*
G01X209306Y171446D02*
X213504D01*
G01X203815Y176937D02*
X209306Y171446D01*
G01X203815Y176936D02*
Y176937D01*
G01X214043Y172746D02*
X261907Y124882D01*
G01X209845Y172746D02*
X214043D01*
G01X207832Y174759D02*
X209845Y172746D01*
G01X207832Y175947D02*
Y174759D01*
G01X206878Y176901D02*
X207832Y175947D01*
G01X205690Y176901D02*
X206878D01*
G01X204735Y177856D02*
X205690Y176901D01*
G01X204735Y179044D02*
Y177856D01*
G01X203781Y179998D02*
X204735Y179044D01*
G01X202593Y179998D02*
X203781D01*
G01X213396Y177499D02*
X206000Y184895D01*
G01X215726Y177499D02*
X213396D01*
G01X259575Y133650D02*
X215726Y177499D01*
G01X212857Y176199D02*
X204700Y184356D01*
G01X215187Y176199D02*
X212857D01*
G01X259036Y132350D02*
X215187Y176199D01*
G01X206000Y192739D02*
X204214Y194525D01*
G01X206000Y184895D02*
Y192739D01*
G01X204700Y192200D02*
X203675Y193225D01*
G01X204700Y184356D02*
Y192200D01*
G01X232221Y112479D02*
X237825Y106875D01*
G01X221221Y112479D02*
X232221D01*
G01X232760Y113779D02*
X239125Y107414D01*
G01X221760Y113779D02*
X232760D01*
G01X223948Y124750D02*
X238250D01*
G01X224487Y126050D02*
X238789D01*
G01X226000Y128500D02*
X239850D01*
G01X220000Y134500D02*
X226000Y128500D01*
G01X220000Y143108D02*
Y134500D01*
G01X232770Y129800D02*
X234120D01*
G01X231930Y130640D02*
X232770Y129800D01*
G01X230580Y130640D02*
X231930D01*
G01X229740Y129800D02*
X230580Y130640D01*
G01X226539Y129800D02*
X229740D01*
G01X221300Y135039D02*
X226539Y129800D01*
G01X221300Y143647D02*
Y135039D01*
G01X236600Y121000D02*
X222394D01*
G01X237139Y122300D02*
X222933D01*
G01X242661Y97000D02*
X250395D01*
G01X237825Y101836D02*
X242661Y97000D01*
G01X237825Y106875D02*
Y101836D01*
G01X243200Y98300D02*
X250934D01*
G01X239125Y102375D02*
X243200Y98300D01*
G01X239125Y107414D02*
Y102375D01*
G01X238250Y124750D02*
X252486Y110514D01*
G01X238789Y126050D02*
X253025Y111814D01*
G01X239850Y128500D02*
X253900Y114450D01*
G01X250836Y106764D02*
X236600Y121000D01*
G01X251375Y108064D02*
X237139Y122300D01*
G01X240389Y129800D02*
X254439Y115750D01*
G01X237150Y129800D02*
X240389D01*
G01X236310Y130640D02*
X237150Y129800D01*
G01X234960Y130640D02*
X236310D01*
G01X234120Y129800D02*
X234960Y130640D01*
G01X259939Y119600D02*
X237639Y141900D01*
G01X242152Y135548D02*
X241197Y136503D01*
G01X242152Y134360D02*
Y135548D01*
G01X243106Y133406D02*
X242152Y134360D01*
G01X244294Y133406D02*
X243106D01*
G01X259400Y118300D02*
X244294Y133406D01*
G01X236035Y141900D02*
X234875Y143060D01*
G01X237639Y141900D02*
X236035D01*
G01X236185Y140600D02*
X234875Y139290D01*
G01X237100Y140600D02*
X236185D01*
G01X239055Y138645D02*
X237100Y140600D01*
G01X239055Y137457D02*
Y138645D01*
G01X240009Y136503D02*
X239055Y137457D01*
G01X241197Y136503D02*
X240009D01*
G01X254670Y92725D02*
X265354D01*
G01X250395Y97000D02*
X254670Y92725D01*
G01X255209Y94025D02*
X264815D01*
G01X250934Y98300D02*
X255209Y94025D01*
G01X266232Y99625D02*
X259093Y106764D01*
G01X266771Y100925D02*
X259632Y108064D01*
G01X260647Y110514D02*
X267786Y103375D01*
G01X252486Y110514D02*
X260647D01*
G01X261186Y111814D02*
X268325Y104675D01*
G01X253025Y111814D02*
X261186D01*
G01X253900Y114450D02*
X274312D01*
G01X254439Y115750D02*
X274851D01*
G01X283800Y119600D02*
X259939D01*
G01X283261Y118300D02*
X259400D01*
G01X259093Y106764D02*
X250836D01*
G01X259632Y108064D02*
X251375D01*
G01X261368Y123582D02*
X303500D01*
G01X261907Y124882D02*
X303500D01*
G01X293150Y133650D02*
X259575D01*
G01X264766Y132350D02*
X259036D01*
G01X272010Y103375D02*
X277485Y108850D01*
G01X267786Y103375D02*
X272010D01*
G01X271471Y104675D02*
X276946Y110150D01*
G01X268325Y104675D02*
X271471D01*
G01X275118Y95875D02*
X280593Y101350D01*
G01X268504Y95875D02*
X275118D01*
G01X265354Y92725D02*
X268504Y95875D01*
G01X274579Y97175D02*
X280054Y102650D01*
G01X267965Y97175D02*
X274579D01*
G01X264815Y94025D02*
X267965Y97175D01*
G01X273564Y99625D02*
X266232D01*
G01X279039Y105100D02*
X273564Y99625D01*
G01X293850Y105100D02*
X279039D01*
G01X273025Y100925D02*
X266771D01*
G01X278500Y106400D02*
X273025Y100925D01*
G01X277485Y108850D02*
X295550D01*
G01X276946Y110150D02*
X296089D01*
G01X276160Y112600D02*
X297401D01*
G01X274312Y114450D02*
X276160Y112600D01*
G01X276699Y113900D02*
X297940D01*
G01X274851Y115750D02*
X276699Y113900D01*
G01X294389Y106400D02*
X278500D01*
G01X265606Y131510D02*
X264766Y132350D01*
G01X266956Y131510D02*
X265606D01*
G01X267796Y132350D02*
X266956Y131510D01*
G01X269146Y132350D02*
X267796D01*
G01X269986Y131510D02*
X269146Y132350D01*
G01X271336Y131510D02*
X269986D01*
G01X272176Y132350D02*
X271336Y131510D01*
G01X283851Y132350D02*
X272176D01*
G01X292661Y100125D02*
X307136D01*
G01X291436Y101350D02*
X292661Y100125D01*
G01X280593Y101350D02*
X291436D01*
G01X293200Y101425D02*
X307675D01*
G01X291975Y102650D02*
X293200Y101425D01*
G01X280054Y102650D02*
X291975D01*
G01X296625Y102325D02*
X293850Y105100D01*
G01X285425Y117975D02*
X283800Y119600D01*
G01X299778Y117975D02*
X285425D01*
G01X284886Y116675D02*
X283261Y118300D01*
G01X299239Y116675D02*
X284886D01*
G01X297164Y103625D02*
X294389Y106400D01*
G01X295500Y131300D02*
X293150Y133650D01*
G01X284691Y131510D02*
X283851Y132350D01*
G01X286041Y131510D02*
X284691D01*
G01X286881Y132350D02*
X286041Y131510D01*
G01X288231Y132350D02*
X286881D01*
G01X289071Y131510D02*
X288231Y132350D01*
G01X290421Y131510D02*
X289071D01*
G01X291261Y132350D02*
X290421Y131510D01*
G01X292611Y132350D02*
X291261D01*
G01X294961Y130000D02*
X292611Y132350D01*
G01X299200Y105200D02*
X327630D01*
G01X295550Y108850D02*
X299200Y105200D01*
G01X307136Y100125D02*
X312036Y95225D01*
G01X307675Y101425D02*
X312575Y96525D01*
G01X325474Y102325D02*
X296625D01*
G01X326013Y103625D02*
X297164D01*
G01X299739Y106500D02*
X327091D01*
G01X296089Y110150D02*
X299739Y106500D01*
G01X301976Y108025D02*
X325680D01*
G01X297401Y112600D02*
X301976Y108025D01*
G01X302515Y109325D02*
X316381D01*
G01X297940Y113900D02*
X302515Y109325D01*
G01X302640Y115113D02*
X299778Y117975D01*
G01X302641Y115113D02*
X302640D01*
G01X301721Y114193D02*
X299239Y116675D01*
G01X303000Y131300D02*
X295500D01*
G01X303000Y130000D02*
X294961D01*
G01X325036Y95225D02*
X325961Y94300D01*
G01X312036Y95225D02*
X325036D01*
G01X325575Y96525D02*
X326500Y95600D01*
G01X312575Y96525D02*
X325575D01*
G01X326625Y101174D02*
X325474Y102325D01*
G01X325141Y109325D02*
X327000Y111184D01*
G01X323791Y109325D02*
X325141D01*
G01X322951Y110165D02*
X323791Y109325D01*
G01X321601Y110165D02*
X322951D01*
G01X320761Y109325D02*
X321601Y110165D01*
G01X319411Y109325D02*
X320761D01*
G01X318571Y110165D02*
X319411Y109325D01*
G01X317221Y110165D02*
X318571D01*
G01X316381Y109325D02*
X317221Y110165D01*
G01X327630Y105200D02*
X328585Y106155D01*
G01X339211Y98500D02*
X342211Y95500D01*
G01X333889Y98500D02*
X339211D01*
G01X333200Y97811D02*
X333889Y98500D01*
G01X333200Y97162D02*
Y97811D01*
G01X330913Y94875D02*
X333200Y97162D01*
G01X330288Y94875D02*
X330913D01*
G01X329713Y94300D02*
X330288Y94875D01*
G01X325961Y94300D02*
X329713D01*
G01X339750Y99800D02*
X342750Y96800D01*
G01X333350Y99800D02*
X339750D01*
G01X331900Y98350D02*
X333350Y99800D01*
G01X331900Y97701D02*
Y98350D01*
G01X330374Y96175D02*
X331900Y97701D01*
G01X329749Y96175D02*
X330374D01*
G01X329174Y95600D02*
X329749Y96175D01*
G01X326500Y95600D02*
X329174D01*
G01X326625Y99936D02*
Y101174D01*
G01X327961Y98600D02*
X326625Y99936D01*
G01X329500Y98600D02*
X327961D01*
G01X330100Y98000D02*
X329500Y98600D01*
G01X327925Y101713D02*
X326013Y103625D01*
G01X327925Y100475D02*
Y101713D01*
G01X328500Y99900D02*
X327925Y100475D01*
G01X329800Y99900D02*
X328500D01*
G01X330100Y100200D02*
X329800Y99900D01*
G01X340346Y109786D02*
X341186Y108946D01*
G01X338996Y109786D02*
X340346D01*
G01X338156Y108946D02*
X338996Y109786D01*
G01X336806Y108946D02*
X338156D01*
G01X335966Y109786D02*
X336806Y108946D01*
G01X334616Y109786D02*
X335966D01*
G01X334028Y110374D02*
X334616Y109786D01*
G01X332804Y110374D02*
X334028D01*
G01X330727Y108297D02*
X332804Y110374D01*
G01X330727Y107109D02*
Y108297D01*
G01X329773Y106155D02*
X330727Y107109D01*
G01X328585Y106155D02*
X329773D01*
G01X335155Y111086D02*
X345966D01*
G01X334567Y111674D02*
X335155Y111086D01*
G01X332265Y111674D02*
X334567D01*
G01X327091Y106500D02*
X332265Y111674D01*
G01X328300Y110645D02*
Y112400D01*
G01X325680Y108025D02*
X328300Y110645D01*
G01X327000Y111184D02*
Y112400D01*
G01X351113Y95500D02*
X356937Y101324D01*
G01X342211Y95500D02*
X351113D01*
G01X350574Y96800D02*
X356398Y102624D01*
G01X342750Y96800D02*
X350574D01*
G01X355555Y116975D02*
X365375D01*
G01X354715Y116135D02*
X355555Y116975D01*
G01X353365Y116135D02*
X354715D01*
G01X352525Y116975D02*
X353365Y116135D01*
G01X351175Y116975D02*
X352525D01*
G01X349780Y115580D02*
X351175Y116975D01*
G01X349780Y113061D02*
Y115580D01*
G01X346505Y109786D02*
X349780Y113061D01*
G01X343376Y109786D02*
X346505D01*
G01X342536Y108946D02*
X343376Y109786D01*
G01X341186Y108946D02*
X342536D01*
G01X350636Y118275D02*
X364836D01*
G01X348480Y116119D02*
X350636Y118275D01*
G01X348480Y113600D02*
Y116119D01*
G01X345966Y111086D02*
X348480Y113600D01*
G01X365442Y101324D02*
X375596Y111478D01*
G01X356937Y101324D02*
X365442D01*
G01X364903Y102624D02*
X374296Y112017D01*
G01X356398Y102624D02*
X364903D01*
G01X369925Y119738D02*
X370100Y119563D01*
G01X368138Y119738D02*
X369925D01*
G01X365375Y116975D02*
X368138Y119738D01*
G01X371325Y121038D02*
X372700Y119663D01*
G01X364836Y118275D02*
X367599Y121038D01*
G01D02*
X371325D01*
G01X375596Y111478D02*
Y128096D01*
G01X374296Y112017D02*
Y128635D01*
G01X378850Y131350D02*
X379600D01*
G01X375596Y128096D02*
X378850Y131350D01*
G01X378311Y132650D02*
X379600D01*
G01X374296Y128635D02*
X378311Y132650D01*
M02*
